# T6G (Grand Teton) — schematic netlist excerpt (pin names and nets, part order shuffled) for the footprints in the layout excerpt that follows; sources: Cadence DE-HDL packaged netlist, KiCad conversion of 04192023_DAF0TMB3IC0_F0TG_MB_C_brd_V02_OCP.brd

C2501  Q_CAP  22UF 4V 20% X6S  pkg C0402  page 74 : A = PVDD11_S3_P1 ; B = GND
PC6572  Q_CAPP  390UF 2.5V 20% ALUM  pkg SMLF  page 363 : A = P0V9_CPU0_RT_2D ; B = GND
PC8003  Q_CAP  22UF 16V 20% X6S  pkg C0805  page 226 : A = SW_P12V_AUX_PVDD18_S5_P1_FLT ; B = GND

(kicad_pcb
	(version 20260206)
	(generator "pcbnew")
	(generator_version "10.0")
	(general
		(thickness 1.6)
		(legacy_teardrops no)
	)
	(paper "A4")
	(title_block
		(title "04192023_DAF0TMB3IC0_F0TG_MB_C_brd_V02_OCP.brd")
		(comment 1 "Grand Teton / footprints 2214-2216 of 8354")
	)
	(layers
		(0 "F.Cu" signal "TOP")
		(4 "In1.Cu" signal "GND")
		(6 "In2.Cu" signal "IN1")
		(8 "In3.Cu" signal "GND1")
		(10 "In4.Cu" signal "IN2")
		(12 "In5.Cu" signal "GND2")
		(14 "In6.Cu" signal "IN3")
		(16 "In7.Cu" signal "GND3")
		(18 "In8.Cu" signal "VCC")
		(20 "In9.Cu" signal "VCC1")
		(22 "In10.Cu" signal "GND4")
		(24 "In11.Cu" signal "IN4")
		(26 "In12.Cu" signal "GND5")
		(28 "In13.Cu" signal "IN5")
		(30 "In14.Cu" signal "GND6")
		(32 "In15.Cu" signal "IN6")
		(34 "In16.Cu" signal "GND7")
		(2 "B.Cu" signal "BOTTOM")
		(9 "F.Adhes" user "F.Adhesive")
		(11 "B.Adhes" user "B.Adhesive")
		(13 "F.Paste" user "Package Geometry/Pastemask Top")
		(15 "B.Paste" user "Package Geometry/Pastemask Bottom")
		(5 "F.SilkS" user "Ref Des/Silkscreen Top")
		(7 "B.SilkS" user "Ref Des/Silkscreen Bottom")
		(1 "F.Mask" user "Board Geometry/Soldermask Top")
		(3 "B.Mask" user "Board Geometry/Soldermask Bottom")
		(17 "Dwgs.User" user "User.Drawings")
		(19 "Cmts.User" user "User.Comments")
		(21 "Eco1.User" user "User.Eco1")
		(23 "Eco2.User" user "User.Eco2")
		(25 "Edge.Cuts" user "Board Geometry/Outline")
		(27 "Margin" user)
		(31 "F.CrtYd" user "Package Geometry/Place Bound Top")
		(29 "B.CrtYd" user "Package Geometry/Place Bound Bottom")
		(35 "F.Fab" user "Ref Des/Assembly Top")
		(33 "B.Fab" user "Ref Des/Assembly Bottom")
	)
	(footprint ""
		(layer "F.Cu")
		(at 462.147666 -380.13767 -90)
		(property "Reference" "PC6572"
			(at 4.62534 2.153666 0)
			(unlocked yes)
			(layer "F.SilkS")
			(effects
				(font
					(size 0.7874 0.5842)
					(thickness 0.1524)
				)
				(justify left)
			)
		)
		(property "Value" ""
			(at 0 0 270)
			(layer "F.Fab")
			(effects
				(font
					(size 1.27 1.27)
				)
			)
		)
		(duplicate_pad_numbers_are_jumpers no)
		(fp_line
			(start -1.988058 2.750058)
			(end 2.750058 2.750058)
			(stroke
				(width 0.1524)
				(type default)
			)
			(layer "F.SilkS")
		)
		(fp_line
			(start 2.750058 2.750058)
			(end 2.750058 0.9398)
			(stroke
				(width 0.1524)
				(type default)
			)
			(layer "F.SilkS")
		)
		(fp_line
			(start -2.750058 1.988058)
			(end -1.988058 2.750058)
			(stroke
				(width 0.1524)
				(type default)
			)
			(layer "F.SilkS")
		)
		(fp_line
			(start -2.750058 0.9398)
			(end -2.750058 1.988058)
			(stroke
				(width 0.1524)
				(type default)
			)
			(layer "F.SilkS")
		)
		(fp_line
			(start 2.750058 -0.9398)
			(end 2.750058 -2.750058)
			(stroke
				(width 0.1524)
				(type default)
			)
			(layer "F.SilkS")
		)
		(fp_line
			(start -2.750058 -1.988058)
			(end -2.750058 -0.9398)
			(stroke
				(width 0.1524)
				(type default)
			)
			(layer "F.SilkS")
		)
		(fp_line
			(start -1.988058 -2.750058)
			(end -2.750058 -1.988058)
			(stroke
				(width 0.1524)
				(type default)
			)
			(layer "F.SilkS")
		)
		(fp_line
			(start 2.750058 -2.750058)
			(end -1.988058 -2.750058)
			(stroke
				(width 0.1524)
				(type default)
			)
			(layer "F.SilkS")
		)
		(fp_line
			(start -2.750058 2.750058)
			(end 2.750058 2.750058)
			(stroke
				(width 0.1)
				(type default)
			)
			(layer "F.Fab")
		)
		(fp_line
			(start 2.750058 2.750058)
			(end 2.750058 -2.750058)
			(stroke
				(width 0.1)
				(type default)
			)
			(layer "F.Fab")
		)
		(fp_line
			(start -2.750058 -2.750058)
			(end -2.750058 2.750058)
			(stroke
				(width 0.1)
				(type default)
			)
			(layer "F.Fab")
		)
		(fp_line
			(start 2.750058 -2.750058)
			(end -2.750058 -2.750058)
			(stroke
				(width 0.1)
				(type default)
			)
			(layer "F.Fab")
		)
		(pad "1" smd rect
			(at -2.199894 0)
			(size 1.6002 3.0226)
			(layers "F.Cu" "F.Mask" "F.Paste")
			(net "P0V9_CPU0_RT_2D")
		)
		(pad "2" smd rect
			(at 2.199894 0)
			(size 1.6002 3.0226)
			(layers "F.Cu" "F.Mask" "F.Paste")
			(net "GND")
		)
	)
	(footprint ""
		(layer "F.Cu")
		(at 80.762094 -152.999694 90)
		(property "Reference" "PC8003"
			(at 0 0 90)
			(layer "F.SilkS")
			(hide yes)
			(effects
				(font
					(size 1.27 1.27)
				)
			)
		)
		(property "Value" ""
			(at 0 0 90)
			(layer "F.Fab")
			(effects
				(font
					(size 1.27 1.27)
				)
			)
		)
		(duplicate_pad_numbers_are_jumpers no)
		(fp_line
			(start 1.524 -0.762)
			(end 1.524 0.762)
			(stroke
				(width 0.1524)
				(type default)
			)
			(layer "F.SilkS")
		)
		(fp_line
			(start -1.524 -0.762)
			(end 1.524 -0.762)
			(stroke
				(width 0.1524)
				(type default)
			)
			(layer "F.SilkS")
		)
		(fp_line
			(start 1.524 0.762)
			(end -1.524 0.762)
			(stroke
				(width 0.1524)
				(type default)
			)
			(layer "F.SilkS")
		)
		(fp_line
			(start -1.524 0.762)
			(end -1.524 -0.762)
			(stroke
				(width 0.1524)
				(type default)
			)
			(layer "F.SilkS")
		)
		(fp_line
			(start 1.1049 -0.724916)
			(end -1.1049 -0.724916)
			(stroke
				(width 0.1)
				(type default)
			)
			(layer "F.Fab")
		)
		(fp_line
			(start -1.1049 -0.724916)
			(end -1.1049 0.724916)
			(stroke
				(width 0.1)
				(type default)
			)
			(layer "F.Fab")
		)
		(fp_line
			(start 1.1049 0.724916)
			(end 1.1049 -0.724916)
			(stroke
				(width 0.1)
				(type default)
			)
			(layer "F.Fab")
		)
		(fp_line
			(start -1.1049 0.724916)
			(end 1.1049 0.724916)
			(stroke
				(width 0.1)
				(type default)
			)
			(layer "F.Fab")
		)
		(pad "1" smd rect
			(at -0.889 0 270)
			(size 1.016 1.27)
			(layers "F.Cu" "F.Mask" "F.Paste")
			(net "SW_P12V_AUX_PVDD18_S5_P1_FLT")
		)
		(pad "2" smd rect
			(at 0.889 0 270)
			(size 1.016 1.27)
			(layers "F.Cu" "F.Mask" "F.Paste")
			(net "GND")
		)
	)
	(footprint ""
		(layer "F.Cu")
		(at 114.327178 -261.748016 -90)
		(property "Reference" "C2501"
			(at 0 0 270)
			(layer "F.SilkS")
			(hide yes)
			(effects
				(font
					(size 1.27 1.27)
				)
			)
		)
		(property "Value" ""
			(at 0 0 270)
			(layer "F.Fab")
			(effects
				(font
					(size 1.27 1.27)
				)
			)
		)
		(duplicate_pad_numbers_are_jumpers no)
		(fp_line
			(start -0.7874 0.4064)
			(end -0.7874 -0.4064)
			(stroke
				(width 0.1524)
				(type default)
			)
			(layer "F.SilkS")
		)
		(fp_line
			(start 0.7874 0.4064)
			(end -0.7874 0.4064)
			(stroke
				(width 0.1524)
				(type default)
			)
			(layer "F.SilkS")
		)
		(fp_line
			(start -0.7874 -0.4064)
			(end 0.7874 -0.4064)
			(stroke
				(width 0.1524)
				(type default)
			)
			(layer "F.SilkS")
		)
		(fp_line
			(start 0.7874 -0.4064)
			(end 0.7874 0.4064)
			(stroke
				(width 0.1524)
				(type default)
			)
			(layer "F.SilkS")
		)
		(fp_line
			(start -0.67945 0.3048)
			(end -0.67945 -0.305054)
			(stroke
				(width 0.1)
				(type default)
			)
			(layer "F.Fab")
		)
		(fp_line
			(start -0.12065 0.3048)
			(end -0.67945 0.3048)
			(stroke
				(width 0.1)
				(type default)
			)
			(layer "F.Fab")
		)
		(fp_line
			(start 0.120396 0.3048)
			(end 0.120396 0.2794)
			(stroke
				(width 0.1)
				(type default)
			)
			(layer "F.Fab")
		)
		(fp_line
			(start 0.67945 0.3048)
			(end 0.120396 0.3048)
			(stroke
				(width 0.1)
				(type default)
			)
			(layer "F.Fab")
		)
		(fp_line
			(start -0.12065 0.2794)
			(end -0.12065 0.3048)
			(stroke
				(width 0.1)
				(type default)
			)
			(layer "F.Fab")
		)
		(fp_line
			(start 0.120396 0.2794)
			(end -0.12065 0.2794)
			(stroke
				(width 0.1)
				(type default)
			)
			(layer "F.Fab")
		)
		(fp_line
			(start -0.12065 -0.2794)
			(end 0.12065 -0.2794)
			(stroke
				(width 0.1)
				(type default)
			)
			(layer "F.Fab")
		)
		(fp_line
			(start 0.12065 -0.2794)
			(end 0.12065 -0.3048)
			(stroke
				(width 0.1)
				(type default)
			)
			(layer "F.Fab")
		)
		(fp_line
			(start 0.12065 -0.3048)
			(end 0.67945 -0.3048)
			(stroke
				(width 0.1)
				(type default)
			)
			(layer "F.Fab")
		)
		(fp_line
			(start 0.67945 -0.3048)
			(end 0.67945 0.3048)
			(stroke
				(width 0.1)
				(type default)
			)
			(layer "F.Fab")
		)
		(fp_line
			(start -0.67945 -0.305054)
			(end -0.12065 -0.305054)
			(stroke
				(width 0.1)
				(type default)
			)
			(layer "F.Fab")
		)
		(fp_line
			(start -0.12065 -0.305054)
			(end -0.12065 -0.2794)
			(stroke
				(width 0.1)
				(type default)
			)
			(layer "F.Fab")
		)
		(pad "1" smd circle
			(at -0.40005 0 270)
			(size 0 0)
			(layers "F.Cu" "F.Mask" "F.Paste")
			(net "PVDD11_S3_P1")
		)
		(pad "2" smd circle
			(at 0.40005 0 270)
			(size 0 0)
			(layers "F.Cu" "F.Mask" "F.Paste")
			(net "GND")
		)
	)
)
